# T6G (Grand Teton) — schematic netlist excerpt (pin names and nets, part order shuffled) for the footprints in the layout excerpt that follows; sources: Cadence DE-HDL packaged netlist, KiCad conversion of 04192023_DAF0TMB3IC0_F0TG_MB_C_brd_V02_OCP.brd

R6704  Q_RES  0 5% EMPTY  pkg 0603LF  page 323 : A = P0V9_CPU1_RT_2D ; B = P0V9_CPU1_RT0_2A_2D
R3635  Q_RES  0.002 1% CHIP  pkg 2512LF  page 237 : A = P12V_SCM ; B = P12V_SCM_R
C6524  Q_CAP_DIFFBUS  DIFF BUS_0.22UF 6.3V 20% X6S  pkg C0201  page 275 : \1\ = P5E_CPU0_P0_TX_BUF_C_DN<11> ; \2\ = P5E_CPU0_P0_TX_BUF_DN<11>
C885  Q_CAP_DIFFBUS  DIFF BUS_0.22UF 6.3V 20% X6S  pkg C0201  page 64 : \1\ = P5E_CPU0_P3_TX_C_DP<8> ; \2\ = P5E_CPU0_P3_TX_DP<8>

(kicad_pcb
	(version 20260206)
	(generator "pcbnew")
	(generator_version "10.0")
	(general
		(thickness 1.6)
		(legacy_teardrops no)
	)
	(paper "A4")
	(title_block
		(title "04192023_DAF0TMB3IC0_F0TG_MB_C_brd_V02_OCP.brd")
		(comment 1 "Grand Teton / footprints 1195-1198 of 8354")
	)
	(layers
		(0 "F.Cu" signal "TOP")
		(4 "In1.Cu" signal "GND")
		(6 "In2.Cu" signal "IN1")
		(8 "In3.Cu" signal "GND1")
		(10 "In4.Cu" signal "IN2")
		(12 "In5.Cu" signal "GND2")
		(14 "In6.Cu" signal "IN3")
		(16 "In7.Cu" signal "GND3")
		(18 "In8.Cu" signal "VCC")
		(20 "In9.Cu" signal "VCC1")
		(22 "In10.Cu" signal "GND4")
		(24 "In11.Cu" signal "IN4")
		(26 "In12.Cu" signal "GND5")
		(28 "In13.Cu" signal "IN5")
		(30 "In14.Cu" signal "GND6")
		(32 "In15.Cu" signal "IN6")
		(34 "In16.Cu" signal "GND7")
		(2 "B.Cu" signal "BOTTOM")
		(9 "F.Adhes" user "F.Adhesive")
		(11 "B.Adhes" user "B.Adhesive")
		(13 "F.Paste" user "Package Geometry/Pastemask Top")
		(15 "B.Paste" user "Package Geometry/Pastemask Bottom")
		(5 "F.SilkS" user "Ref Des/Silkscreen Top")
		(7 "B.SilkS" user "Ref Des/Silkscreen Bottom")
		(1 "F.Mask" user "Board Geometry/Soldermask Top")
		(3 "B.Mask" user "Board Geometry/Soldermask Bottom")
		(17 "Dwgs.User" user "User.Drawings")
		(19 "Cmts.User" user "User.Comments")
		(21 "Eco1.User" user "User.Eco1")
		(23 "Eco2.User" user "User.Eco2")
		(25 "Edge.Cuts" user "Board Geometry/Outline")
		(27 "Margin" user)
		(31 "F.CrtYd" user "Package Geometry/Place Bound Top")
		(29 "B.CrtYd" user "Package Geometry/Place Bound Bottom")
		(35 "F.Fab" user "Ref Des/Assembly Top")
		(33 "B.Fab" user "Ref Des/Assembly Bottom")
	)
	(footprint ""
		(layer "F.Cu")
		(at 44.623228 -399.41246)
		(property "Reference" "R6704"
			(at 0 0 0)
			(layer "F.SilkS")
			(hide yes)
			(effects
				(font
					(size 1.27 1.27)
				)
			)
		)
		(property "Value" ""
			(at 0 0 0)
			(layer "F.Fab")
			(effects
				(font
					(size 1.27 1.27)
				)
			)
		)
		(duplicate_pad_numbers_are_jumpers no)
		(fp_line
			(start -1.2954 -0.5842)
			(end 1.2954 -0.5842)
			(stroke
				(width 0.1524)
				(type default)
			)
			(layer "F.SilkS")
		)
		(fp_line
			(start -1.2954 0.5842)
			(end -1.2954 -0.5842)
			(stroke
				(width 0.1524)
				(type default)
			)
			(layer "F.SilkS")
		)
		(fp_line
			(start 1.2954 -0.5842)
			(end 1.2954 0.5842)
			(stroke
				(width 0.1524)
				(type default)
			)
			(layer "F.SilkS")
		)
		(fp_line
			(start 1.2954 0.5842)
			(end -1.2954 0.5842)
			(stroke
				(width 0.1524)
				(type default)
			)
			(layer "F.SilkS")
		)
		(fp_line
			(start -1.1938 -0.406654)
			(end -0.8636 -0.406654)
			(stroke
				(width 0.1)
				(type default)
			)
			(layer "F.Fab")
		)
		(fp_line
			(start -1.1938 0.4064)
			(end -1.1938 -0.406654)
			(stroke
				(width 0.1)
				(type default)
			)
			(layer "F.Fab")
		)
		(fp_line
			(start -0.8636 -0.4572)
			(end 0.8636 -0.4572)
			(stroke
				(width 0.1)
				(type default)
			)
			(layer "F.Fab")
		)
		(fp_line
			(start -0.8636 -0.406654)
			(end -0.8636 -0.4572)
			(stroke
				(width 0.1)
				(type default)
			)
			(layer "F.Fab")
		)
		(fp_line
			(start -0.8636 0.4064)
			(end -1.1938 0.4064)
			(stroke
				(width 0.1)
				(type default)
			)
			(layer "F.Fab")
		)
		(fp_line
			(start -0.8636 0.4318)
			(end -0.8636 0.4064)
			(stroke
				(width 0.1)
				(type default)
			)
			(layer "F.Fab")
		)
		(fp_line
			(start -0.8636 0.4572)
			(end -0.8636 0.4318)
			(stroke
				(width 0.1)
				(type default)
			)
			(layer "F.Fab")
		)
		(fp_line
			(start 0.8636 -0.4572)
			(end 0.8636 -0.406654)
			(stroke
				(width 0.1)
				(type default)
			)
			(layer "F.Fab")
		)
		(fp_line
			(start 0.8636 -0.406654)
			(end 1.1938 -0.406654)
			(stroke
				(width 0.1)
				(type default)
			)
			(layer "F.Fab")
		)
		(fp_line
			(start 0.8636 0.4064)
			(end 0.8636 0.4572)
			(stroke
				(width 0.1)
				(type default)
			)
			(layer "F.Fab")
		)
		(fp_line
			(start 0.8636 0.4572)
			(end -0.8636 0.4572)
			(stroke
				(width 0.1)
				(type default)
			)
			(layer "F.Fab")
		)
		(fp_line
			(start 1.1938 -0.406654)
			(end 1.1938 0.4064)
			(stroke
				(width 0.1)
				(type default)
			)
			(layer "F.Fab")
		)
		(fp_line
			(start 1.1938 0.4064)
			(end 0.8636 0.4064)
			(stroke
				(width 0.1)
				(type default)
			)
			(layer "F.Fab")
		)
		(pad "1" smd rect
			(at -0.7366 0 270)
			(size 0.7112 0.8128)
			(layers "F.Cu" "F.Mask" "F.Paste")
			(net "P0V9_CPU1_RT_2D")
		)
		(pad "2" smd rect
			(at 0.7366 0 270)
			(size 0.7112 0.8128)
			(layers "F.Cu" "F.Mask" "F.Paste")
			(net "P0V9_CPU1_RT0_2A_2D")
		)
	)
	(footprint ""
		(layer "F.Cu")
		(at 337.464146 -416.899344 -90)
		(property "Reference" "C6524"
			(at 0 0 270)
			(layer "F.SilkS")
			(hide yes)
			(effects
				(font
					(size 1.27 1.27)
				)
			)
		)
		(property "Value" ""
			(at 0 0 270)
			(layer "F.Fab")
			(effects
				(font
					(size 1.27 1.27)
				)
			)
		)
		(duplicate_pad_numbers_are_jumpers no)
		(fp_line
			(start -0.299974 0.150114)
			(end -0.299974 -0.150114)
			(stroke
				(width 0.1)
				(type default)
			)
			(layer "F.Fab")
		)
		(fp_line
			(start 0.299974 0.150114)
			(end -0.299974 0.150114)
			(stroke
				(width 0.1)
				(type default)
			)
			(layer "F.Fab")
		)
		(fp_line
			(start -0.299974 -0.150114)
			(end 0.299974 -0.150114)
			(stroke
				(width 0.1)
				(type default)
			)
			(layer "F.Fab")
		)
		(fp_line
			(start 0.299974 -0.150114)
			(end 0.299974 0.150114)
			(stroke
				(width 0.1)
				(type default)
			)
			(layer "F.Fab")
		)
		(pad "1" smd rect
			(at -0.2667 0 270)
			(size 0.3048 0.381)
			(layers "F.Cu" "F.Mask" "F.Paste")
			(net "P5E_CPU0_P0_TX_BUF_C_DN<11>")
		)
		(pad "2" smd rect
			(at 0.2667 0 270)
			(size 0.3048 0.381)
			(layers "F.Cu" "F.Mask" "F.Paste")
			(net "P5E_CPU0_P0_TX_BUF_DN<11>")
		)
	)
	(footprint ""
		(layer "F.Cu")
		(at 201.047604 -34.923984 90)
		(property "Reference" "R3635"
			(at 5.299456 -1.945132 0)
			(unlocked yes)
			(layer "F.SilkS")
			(effects
				(font
					(size 0.7874 0.5842)
					(thickness 0.1524)
				)
				(justify left)
			)
		)
		(property "Value" ""
			(at 0 0 90)
			(layer "F.Fab")
			(effects
				(font
					(size 1.27 1.27)
				)
			)
		)
		(duplicate_pad_numbers_are_jumpers no)
		(fp_line
			(start 3.937508 -1.8796)
			(end -3.937508 -1.8796)
			(stroke
				(width 0.1524)
				(type default)
			)
			(layer "F.SilkS")
		)
		(fp_line
			(start -3.937508 -1.8796)
			(end -3.937508 1.8796)
			(stroke
				(width 0.1524)
				(type default)
			)
			(layer "F.SilkS")
		)
		(fp_line
			(start 3.937508 1.8796)
			(end 3.937508 -1.8796)
			(stroke
				(width 0.1524)
				(type default)
			)
			(layer "F.SilkS")
		)
		(fp_line
			(start -3.937508 1.8796)
			(end 3.937508 1.8796)
			(stroke
				(width 0.1524)
				(type default)
			)
			(layer "F.SilkS")
		)
		(fp_line
			(start 3.275076 -1.674876)
			(end -3.275076 -1.674876)
			(stroke
				(width 0.1)
				(type default)
			)
			(layer "F.Fab")
		)
		(fp_line
			(start -3.275076 -1.674876)
			(end -3.275076 1.674876)
			(stroke
				(width 0.1)
				(type default)
			)
			(layer "F.Fab")
		)
		(fp_line
			(start 3.275076 1.674876)
			(end 3.275076 -1.674876)
			(stroke
				(width 0.1)
				(type default)
			)
			(layer "F.Fab")
		)
		(fp_line
			(start -3.275076 1.674876)
			(end 3.275076 1.674876)
			(stroke
				(width 0.1)
				(type default)
			)
			(layer "F.Fab")
		)
		(pad "1" smd rect
			(at -2.350008 0 90)
			(size 2.921 3.5052)
			(layers "F.Cu" "F.Mask" "F.Paste")
			(net "P12V_SCM")
		)
		(pad "2" smd rect
			(at 2.350008 0 90)
			(size 2.921 3.5052)
			(layers "F.Cu" "F.Mask" "F.Paste")
			(net "P12V_SCM_R")
		)
	)
	(footprint ""
		(layer "F.Cu")
		(at 379.704092 -381.41783 -90)
		(property "Reference" "C885"
			(at 0 0 270)
			(layer "F.SilkS")
			(hide yes)
			(effects
				(font
					(size 1.27 1.27)
				)
			)
		)
		(property "Value" ""
			(at 0 0 270)
			(layer "F.Fab")
			(effects
				(font
					(size 1.27 1.27)
				)
			)
		)
		(duplicate_pad_numbers_are_jumpers no)
		(fp_line
			(start -0.299974 0.150114)
			(end -0.299974 -0.150114)
			(stroke
				(width 0.1)
				(type default)
			)
			(layer "F.Fab")
		)
		(fp_line
			(start 0.299974 0.150114)
			(end -0.299974 0.150114)
			(stroke
				(width 0.1)
				(type default)
			)
			(layer "F.Fab")
		)
		(fp_line
			(start -0.299974 -0.150114)
			(end 0.299974 -0.150114)
			(stroke
				(width 0.1)
				(type default)
			)
			(layer "F.Fab")
		)
		(fp_line
			(start 0.299974 -0.150114)
			(end 0.299974 0.150114)
			(stroke
				(width 0.1)
				(type default)
			)
			(layer "F.Fab")
		)
		(pad "1" smd rect
			(at -0.2667 0 270)
			(size 0.3048 0.381)
			(layers "F.Cu" "F.Mask" "F.Paste")
			(net "P5E_CPU0_P3_TX_C_DP<8>")
		)
		(pad "2" smd rect
			(at 0.2667 0 270)
			(size 0.3048 0.381)
			(layers "F.Cu" "F.Mask" "F.Paste")
			(net "P5E_CPU0_P3_TX_DP<8>")
		)
	)
)
